(kicad_pcb
	(version 20260206)
	(generator "pcbnew")
	(generator_version "10.0")
	(general
		(thickness 1.6)
		(legacy_teardrops no)
	)
	(paper "A4")
	(title_block
		(title "03242023_DA0F0TMBIJ0_F0T_Motherboard_J_brd_V01_OCP.brd")
		(comment 1 "Grand Teton / footprints 4153-4158 of 6105")
	)
	(layers
		(0 "F.Cu" signal "TOP")
		(4 "In1.Cu" signal "GND")
		(6 "In2.Cu" signal "IN1")
		(8 "In3.Cu" signal "GND1")
		(10 "In4.Cu" signal "IN2")
		(12 "In5.Cu" signal "GND2")
		(14 "In6.Cu" signal "IN3")
		(16 "In7.Cu" signal "GND3")
		(18 "In8.Cu" signal "VCC")
		(20 "In9.Cu" signal "VCC1")
		(22 "In10.Cu" signal "GND4")
		(24 "In11.Cu" signal "IN4")
		(26 "In12.Cu" signal "GND5")
		(28 "In13.Cu" signal "IN5")
		(30 "In14.Cu" signal "GND6")
		(32 "In15.Cu" signal "IN6")
		(34 "In16.Cu" signal "GND7")
		(2 "B.Cu" signal "BOTTOM")
		(9 "F.Adhes" user "F.Adhesive")
		(11 "B.Adhes" user "B.Adhesive")
		(13 "F.Paste" user "Package Geometry/Pastemask Top")
		(15 "B.Paste" user "Package Geometry/Pastemask Bottom")
		(5 "F.SilkS" user "Ref Des/Silkscreen Top")
		(7 "B.SilkS" user "Ref Des/Silkscreen Bottom")
		(1 "F.Mask" user "Board Geometry/Soldermask Top")
		(3 "B.Mask" user "Board Geometry/Soldermask Bottom")
		(17 "Dwgs.User" user "User.Drawings")
		(19 "Cmts.User" user "User.Comments")
		(21 "Eco1.User" user "User.Eco1")
		(23 "Eco2.User" user "User.Eco2")
		(25 "Edge.Cuts" user "Board Geometry/Outline")
		(27 "Margin" user)
		(31 "F.CrtYd" user "Package Geometry/Place Bound Top")
		(29 "B.CrtYd" user "Package Geometry/Place Bound Bottom")
		(35 "F.Fab" user "Ref Des/Assembly Top")
		(33 "B.Fab" user "Ref Des/Assembly Bottom")
	)
	(footprint ""
		(layer "B.Cu")
		(at 37.599366 -192.924176 -90)
		(property "Reference" "R820"
			(at 0 0 90)
			(layer "B.SilkS")
			(hide yes)
			(effects
				(font
					(size 1.27 1.27)
				)
				(justify mirror)
			)
		)
		(property "Value" ""
			(at 0 0 90)
			(layer "B.Fab")
			(effects
				(font
					(size 1.27 1.27)
				)
				(justify mirror)
			)
		)
		(duplicate_pad_numbers_are_jumpers no)
		(fp_line
			(start -0.7874 0.4064)
			(end 0.7874 0.4064)
			(stroke
				(width 0.1524)
				(type default)
			)
			(layer "B.SilkS")
		)
		(fp_line
			(start 0.7874 0.4064)
			(end 0.7874 -0.4064)
			(stroke
				(width 0.1524)
				(type default)
			)
			(layer "B.SilkS")
		)
		(fp_line
			(start -0.7874 -0.4064)
			(end -0.7874 0.4064)
			(stroke
				(width 0.1524)
				(type default)
			)
			(layer "B.SilkS")
		)
		(fp_line
			(start 0.7874 -0.4064)
			(end -0.7874 -0.4064)
			(stroke
				(width 0.1524)
				(type default)
			)
			(layer "B.SilkS")
		)
		(fp_line
			(start -0.67945 0.3048)
			(end -0.120396 0.3048)
			(stroke
				(width 0.1)
				(type default)
			)
			(layer "B.Fab")
		)
		(fp_line
			(start -0.120396 0.3048)
			(end -0.120396 0.2794)
			(stroke
				(width 0.1)
				(type default)
			)
			(layer "B.Fab")
		)
		(fp_line
			(start 0.12065 0.3048)
			(end 0.67945 0.3048)
			(stroke
				(width 0.1)
				(type default)
			)
			(layer "B.Fab")
		)
		(fp_line
			(start 0.67945 0.3048)
			(end 0.67945 -0.305054)
			(stroke
				(width 0.1)
				(type default)
			)
			(layer "B.Fab")
		)
		(fp_line
			(start -0.120396 0.2794)
			(end 0.12065 0.2794)
			(stroke
				(width 0.1)
				(type default)
			)
			(layer "B.Fab")
		)
		(fp_line
			(start 0.12065 0.2794)
			(end 0.12065 0.3048)
			(stroke
				(width 0.1)
				(type default)
			)
			(layer "B.Fab")
		)
		(fp_line
			(start -0.12065 -0.2794)
			(end -0.12065 -0.3048)
			(stroke
				(width 0.1)
				(type default)
			)
			(layer "B.Fab")
		)
		(fp_line
			(start 0.12065 -0.2794)
			(end -0.12065 -0.2794)
			(stroke
				(width 0.1)
				(type default)
			)
			(layer "B.Fab")
		)
		(fp_line
			(start -0.67945 -0.3048)
			(end -0.67945 0.3048)
			(stroke
				(width 0.1)
				(type default)
			)
			(layer "B.Fab")
		)
		(fp_line
			(start -0.12065 -0.3048)
			(end -0.67945 -0.3048)
			(stroke
				(width 0.1)
				(type default)
			)
			(layer "B.Fab")
		)
		(fp_line
			(start 0.12065 -0.305054)
			(end 0.12065 -0.2794)
			(stroke
				(width 0.1)
				(type default)
			)
			(layer "B.Fab")
		)
		(fp_line
			(start 0.67945 -0.305054)
			(end 0.12065 -0.305054)
			(stroke
				(width 0.1)
				(type default)
			)
			(layer "B.Fab")
		)
		(pad "1" smd circle
			(at 0.40005 0 90)
			(size 0 0)
			(layers "B.Cu" "B.Mask" "B.Paste")
			(net "PVCCD_HV_CPU1")
		)
		(pad "2" smd circle
			(at -0.40005 0 90)
			(size 0 0)
			(layers "B.Cu" "B.Mask" "B.Paste")
			(net "RST_M_AB_CPU1_FPGA_N")
		)
	)
	(footprint ""
		(layer "B.Cu")
		(at 216.20988 -53.177948)
		(property "Reference" "C2067"
			(at 0 0 0)
			(layer "B.SilkS")
			(hide yes)
			(effects
				(font
					(size 1.27 1.27)
				)
				(justify mirror)
			)
		)
		(property "Value" ""
			(at 0 0 0)
			(layer "B.Fab")
			(effects
				(font
					(size 1.27 1.27)
				)
				(justify mirror)
			)
		)
		(duplicate_pad_numbers_are_jumpers no)
		(fp_line
			(start -0.7874 -0.4064)
			(end -0.7874 0.4064)
			(stroke
				(width 0.1524)
				(type default)
			)
			(layer "B.SilkS")
		)
		(fp_line
			(start -0.7874 0.4064)
			(end 0.7874 0.4064)
			(stroke
				(width 0.1524)
				(type default)
			)
			(layer "B.SilkS")
		)
		(fp_line
			(start 0.7874 -0.4064)
			(end -0.7874 -0.4064)
			(stroke
				(width 0.1524)
				(type default)
			)
			(layer "B.SilkS")
		)
		(fp_line
			(start 0.7874 0.4064)
			(end 0.7874 -0.4064)
			(stroke
				(width 0.1524)
				(type default)
			)
			(layer "B.SilkS")
		)
		(fp_line
			(start -0.67945 -0.3048)
			(end -0.67945 0.3048)
			(stroke
				(width 0.1)
				(type default)
			)
			(layer "B.Fab")
		)
		(fp_line
			(start -0.67945 0.3048)
			(end -0.120396 0.3048)
			(stroke
				(width 0.1)
				(type default)
			)
			(layer "B.Fab")
		)
		(fp_line
			(start -0.12065 -0.3048)
			(end -0.67945 -0.3048)
			(stroke
				(width 0.1)
				(type default)
			)
			(layer "B.Fab")
		)
		(fp_line
			(start -0.12065 -0.2794)
			(end -0.12065 -0.3048)
			(stroke
				(width 0.1)
				(type default)
			)
			(layer "B.Fab")
		)
		(fp_line
			(start -0.120396 0.2794)
			(end 0.12065 0.2794)
			(stroke
				(width 0.1)
				(type default)
			)
			(layer "B.Fab")
		)
		(fp_line
			(start -0.120396 0.3048)
			(end -0.120396 0.2794)
			(stroke
				(width 0.1)
				(type default)
			)
			(layer "B.Fab")
		)
		(fp_line
			(start 0.12065 -0.305054)
			(end 0.12065 -0.2794)
			(stroke
				(width 0.1)
				(type default)
			)
			(layer "B.Fab")
		)
		(fp_line
			(start 0.12065 -0.2794)
			(end -0.12065 -0.2794)
			(stroke
				(width 0.1)
				(type default)
			)
			(layer "B.Fab")
		)
		(fp_line
			(start 0.12065 0.2794)
			(end 0.12065 0.3048)
			(stroke
				(width 0.1)
				(type default)
			)
			(layer "B.Fab")
		)
		(fp_line
			(start 0.12065 0.3048)
			(end 0.67945 0.3048)
			(stroke
				(width 0.1)
				(type default)
			)
			(layer "B.Fab")
		)
		(fp_line
			(start 0.67945 -0.305054)
			(end 0.12065 -0.305054)
			(stroke
				(width 0.1)
				(type default)
			)
			(layer "B.Fab")
		)
		(fp_line
			(start 0.67945 0.3048)
			(end 0.67945 -0.305054)
			(stroke
				(width 0.1)
				(type default)
			)
			(layer "B.Fab")
		)
		(pad "1" smd circle
			(at 0.40005 0 180)
			(size 0 0)
			(layers "B.Cu" "B.Mask" "B.Paste")
			(net "P3V3_AUX")
		)
		(pad "2" smd circle
			(at -0.40005 0 180)
			(size 0 0)
			(layers "B.Cu" "B.Mask" "B.Paste")
			(net "GND")
		)
	)
	(footprint ""
		(layer "B.Cu")
		(at 338.016342 -50.678842 90)
		(property "Reference" "C1264"
			(at 0 0 90)
			(layer "B.SilkS")
			(hide yes)
			(effects
				(font
					(size 1.27 1.27)
				)
				(justify mirror)
			)
		)
		(property "Value" ""
			(at 0 0 90)
			(layer "B.Fab")
			(effects
				(font
					(size 1.27 1.27)
				)
				(justify mirror)
			)
		)
		(duplicate_pad_numbers_are_jumpers no)
		(fp_line
			(start 0.7874 -0.4064)
			(end -0.7874 -0.4064)
			(stroke
				(width 0.1524)
				(type default)
			)
			(layer "B.SilkS")
		)
		(fp_line
			(start -0.7874 -0.4064)
			(end -0.7874 0.4064)
			(stroke
				(width 0.1524)
				(type default)
			)
			(layer "B.SilkS")
		)
		(fp_line
			(start 0.7874 0.4064)
			(end 0.7874 -0.4064)
			(stroke
				(width 0.1524)
				(type default)
			)
			(layer "B.SilkS")
		)
		(fp_line
			(start -0.7874 0.4064)
			(end 0.7874 0.4064)
			(stroke
				(width 0.1524)
				(type default)
			)
			(layer "B.SilkS")
		)
		(fp_line
			(start 0.67945 -0.305054)
			(end 0.12065 -0.305054)
			(stroke
				(width 0.1)
				(type default)
			)
			(layer "B.Fab")
		)
		(fp_line
			(start 0.12065 -0.305054)
			(end 0.12065 -0.2794)
			(stroke
				(width 0.1)
				(type default)
			)
			(layer "B.Fab")
		)
		(fp_line
			(start -0.12065 -0.3048)
			(end -0.67945 -0.3048)
			(stroke
				(width 0.1)
				(type default)
			)
			(layer "B.Fab")
		)
		(fp_line
			(start -0.67945 -0.3048)
			(end -0.67945 0.3048)
			(stroke
				(width 0.1)
				(type default)
			)
			(layer "B.Fab")
		)
		(fp_line
			(start 0.12065 -0.2794)
			(end -0.12065 -0.2794)
			(stroke
				(width 0.1)
				(type default)
			)
			(layer "B.Fab")
		)
		(fp_line
			(start -0.12065 -0.2794)
			(end -0.12065 -0.3048)
			(stroke
				(width 0.1)
				(type default)
			)
			(layer "B.Fab")
		)
		(fp_line
			(start 0.12065 0.2794)
			(end 0.12065 0.3048)
			(stroke
				(width 0.1)
				(type default)
			)
			(layer "B.Fab")
		)
		(fp_line
			(start -0.120396 0.2794)
			(end 0.12065 0.2794)
			(stroke
				(width 0.1)
				(type default)
			)
			(layer "B.Fab")
		)
		(fp_line
			(start 0.67945 0.3048)
			(end 0.67945 -0.305054)
			(stroke
				(width 0.1)
				(type default)
			)
			(layer "B.Fab")
		)
		(fp_line
			(start 0.12065 0.3048)
			(end 0.67945 0.3048)
			(stroke
				(width 0.1)
				(type default)
			)
			(layer "B.Fab")
		)
		(fp_line
			(start -0.120396 0.3048)
			(end -0.120396 0.2794)
			(stroke
				(width 0.1)
				(type default)
			)
			(layer "B.Fab")
		)
		(fp_line
			(start -0.67945 0.3048)
			(end -0.120396 0.3048)
			(stroke
				(width 0.1)
				(type default)
			)
			(layer "B.Fab")
		)
		(pad "1" smd circle
			(at 0.40005 0 270)
			(size 0 0)
			(layers "B.Cu" "B.Mask" "B.Paste")
			(net "P1V05_PCH_PLL_AUX")
		)
		(pad "2" smd circle
			(at -0.40005 0 270)
			(size 0 0)
			(layers "B.Cu" "B.Mask" "B.Paste")
			(net "GND")
		)
	)
	(footprint ""
		(layer "B.Cu")
		(at 24.877522 -165.059106 180)
		(property "Reference" "PR4253"
			(at 0 0 0)
			(layer "B.SilkS")
			(hide yes)
			(effects
				(font
					(size 1.27 1.27)
				)
				(justify mirror)
			)
		)
		(property "Value" ""
			(at 0 0 0)
			(layer "B.Fab")
			(effects
				(font
					(size 1.27 1.27)
				)
				(justify mirror)
			)
		)
		(duplicate_pad_numbers_are_jumpers no)
		(fp_line
			(start 0.7874 0.4064)
			(end 0.7874 -0.4064)
			(stroke
				(width 0.1524)
				(type default)
			)
			(layer "B.SilkS")
		)
		(fp_line
			(start 0.7874 -0.4064)
			(end -0.7874 -0.4064)
			(stroke
				(width 0.1524)
				(type default)
			)
			(layer "B.SilkS")
		)
		(fp_line
			(start -0.7874 0.4064)
			(end 0.7874 0.4064)
			(stroke
				(width 0.1524)
				(type default)
			)
			(layer "B.SilkS")
		)
		(fp_line
			(start -0.7874 -0.4064)
			(end -0.7874 0.4064)
			(stroke
				(width 0.1524)
				(type default)
			)
			(layer "B.SilkS")
		)
		(fp_line
			(start 0.67945 0.3048)
			(end 0.67945 -0.305054)
			(stroke
				(width 0.1)
				(type default)
			)
			(layer "B.Fab")
		)
		(fp_line
			(start 0.67945 -0.305054)
			(end 0.12065 -0.305054)
			(stroke
				(width 0.1)
				(type default)
			)
			(layer "B.Fab")
		)
		(fp_line
			(start 0.12065 0.3048)
			(end 0.67945 0.3048)
			(stroke
				(width 0.1)
				(type default)
			)
			(layer "B.Fab")
		)
		(fp_line
			(start 0.12065 0.2794)
			(end 0.12065 0.3048)
			(stroke
				(width 0.1)
				(type default)
			)
			(layer "B.Fab")
		)
		(fp_line
			(start 0.12065 -0.2794)
			(end -0.12065 -0.2794)
			(stroke
				(width 0.1)
				(type default)
			)
			(layer "B.Fab")
		)
		(fp_line
			(start 0.12065 -0.305054)
			(end 0.12065 -0.2794)
			(stroke
				(width 0.1)
				(type default)
			)
			(layer "B.Fab")
		)
		(fp_line
			(start -0.120396 0.3048)
			(end -0.120396 0.2794)
			(stroke
				(width 0.1)
				(type default)
			)
			(layer "B.Fab")
		)
		(fp_line
			(start -0.120396 0.2794)
			(end 0.12065 0.2794)
			(stroke
				(width 0.1)
				(type default)
			)
			(layer "B.Fab")
		)
		(fp_line
			(start -0.12065 -0.2794)
			(end -0.12065 -0.3048)
			(stroke
				(width 0.1)
				(type default)
			)
			(layer "B.Fab")
		)
		(fp_line
			(start -0.12065 -0.3048)
			(end -0.67945 -0.3048)
			(stroke
				(width 0.1)
				(type default)
			)
			(layer "B.Fab")
		)
		(fp_line
			(start -0.67945 0.3048)
			(end -0.120396 0.3048)
			(stroke
				(width 0.1)
				(type default)
			)
			(layer "B.Fab")
		)
		(fp_line
			(start -0.67945 -0.3048)
			(end -0.67945 0.3048)
			(stroke
				(width 0.1)
				(type default)
			)
			(layer "B.Fab")
		)
		(pad "1" smd circle
			(at 0.40005 0)
			(size 0 0)
			(layers "B.Cu" "B.Mask" "B.Paste")
			(net "NC_PVCCD_HV_CPU1_ACSP4")
		)
		(pad "2" smd circle
			(at -0.40005 0)
			(size 0 0)
			(layers "B.Cu" "B.Mask" "B.Paste")
			(net "GND")
		)
	)
	(footprint ""
		(layer "B.Cu")
		(at 110.922054 -334.703166 -90)
		(property "Reference" "PR300"
			(at 0 0 90)
			(layer "B.SilkS")
			(hide yes)
			(effects
				(font
					(size 1.27 1.27)
				)
				(justify mirror)
			)
		)
		(property "Value" ""
			(at 0 0 90)
			(layer "B.Fab")
			(effects
				(font
					(size 1.27 1.27)
				)
				(justify mirror)
			)
		)
		(duplicate_pad_numbers_are_jumpers no)
		(fp_line
			(start -0.7874 0.4064)
			(end 0.7874 0.4064)
			(stroke
				(width 0.1524)
				(type default)
			)
			(layer "B.SilkS")
		)
		(fp_line
			(start 0.7874 0.4064)
			(end 0.7874 -0.4064)
			(stroke
				(width 0.1524)
				(type default)
			)
			(layer "B.SilkS")
		)
		(fp_line
			(start -0.7874 -0.4064)
			(end -0.7874 0.4064)
			(stroke
				(width 0.1524)
				(type default)
			)
			(layer "B.SilkS")
		)
		(fp_line
			(start 0.7874 -0.4064)
			(end -0.7874 -0.4064)
			(stroke
				(width 0.1524)
				(type default)
			)
			(layer "B.SilkS")
		)
		(fp_line
			(start -0.67945 0.3048)
			(end -0.120396 0.3048)
			(stroke
				(width 0.1)
				(type default)
			)
			(layer "B.Fab")
		)
		(fp_line
			(start -0.120396 0.3048)
			(end -0.120396 0.2794)
			(stroke
				(width 0.1)
				(type default)
			)
			(layer "B.Fab")
		)
		(fp_line
			(start 0.12065 0.3048)
			(end 0.67945 0.3048)
			(stroke
				(width 0.1)
				(type default)
			)
			(layer "B.Fab")
		)
		(fp_line
			(start 0.67945 0.3048)
			(end 0.67945 -0.305054)
			(stroke
				(width 0.1)
				(type default)
			)
			(layer "B.Fab")
		)
		(fp_line
			(start -0.120396 0.2794)
			(end 0.12065 0.2794)
			(stroke
				(width 0.1)
				(type default)
			)
			(layer "B.Fab")
		)
		(fp_line
			(start 0.12065 0.2794)
			(end 0.12065 0.3048)
			(stroke
				(width 0.1)
				(type default)
			)
			(layer "B.Fab")
		)
		(fp_line
			(start -0.12065 -0.2794)
			(end -0.12065 -0.3048)
			(stroke
				(width 0.1)
				(type default)
			)
			(layer "B.Fab")
		)
		(fp_line
			(start 0.12065 -0.2794)
			(end -0.12065 -0.2794)
			(stroke
				(width 0.1)
				(type default)
			)
			(layer "B.Fab")
		)
		(fp_line
			(start -0.67945 -0.3048)
			(end -0.67945 0.3048)
			(stroke
				(width 0.1)
				(type default)
			)
			(layer "B.Fab")
		)
		(fp_line
			(start -0.12065 -0.3048)
			(end -0.67945 -0.3048)
			(stroke
				(width 0.1)
				(type default)
			)
			(layer "B.Fab")
		)
		(fp_line
			(start 0.12065 -0.305054)
			(end 0.12065 -0.2794)
			(stroke
				(width 0.1)
				(type default)
			)
			(layer "B.Fab")
		)
		(fp_line
			(start 0.67945 -0.305054)
			(end 0.12065 -0.305054)
			(stroke
				(width 0.1)
				(type default)
			)
			(layer "B.Fab")
		)
		(pad "1" smd circle
			(at 0.40005 0 90)
			(size 0 0)
			(layers "B.Cu" "B.Mask" "B.Paste")
			(net "PVCCIN_CPU1_PVCC")
		)
		(pad "2" smd circle
			(at -0.40005 0 90)
			(size 0 0)
			(layers "B.Cu" "B.Mask" "B.Paste")
			(net "PVCCIN_CPU1_VDD3")
		)
	)
	(footprint ""
		(layer "B.Cu")
		(at 184.912 -20.284948 90)
		(property "Reference" "R4512"
			(at 0 0 90)
			(layer "B.SilkS")
			(hide yes)
			(effects
				(font
					(size 1.27 1.27)
				)
				(justify mirror)
			)
		)
		(property "Value" ""
			(at 0 0 90)
			(layer "B.Fab")
			(effects
				(font
					(size 1.27 1.27)
				)
				(justify mirror)
			)
		)
		(duplicate_pad_numbers_are_jumpers no)
		(fp_line
			(start 0.7874 -0.4064)
			(end -0.7874 -0.4064)
			(stroke
				(width 0.1524)
				(type default)
			)
			(layer "B.SilkS")
		)
		(fp_line
			(start -0.7874 -0.4064)
			(end -0.7874 0.4064)
			(stroke
				(width 0.1524)
				(type default)
			)
			(layer "B.SilkS")
		)
		(fp_line
			(start 0.7874 0.4064)
			(end 0.7874 -0.4064)
			(stroke
				(width 0.1524)
				(type default)
			)
			(layer "B.SilkS")
		)
		(fp_line
			(start -0.7874 0.4064)
			(end 0.7874 0.4064)
			(stroke
				(width 0.1524)
				(type default)
			)
			(layer "B.SilkS")
		)
		(fp_line
			(start 0.67945 -0.305054)
			(end 0.12065 -0.305054)
			(stroke
				(width 0.1)
				(type default)
			)
			(layer "B.Fab")
		)
		(fp_line
			(start 0.12065 -0.305054)
			(end 0.12065 -0.2794)
			(stroke
				(width 0.1)
				(type default)
			)
			(layer "B.Fab")
		)
		(fp_line
			(start -0.12065 -0.3048)
			(end -0.67945 -0.3048)
			(stroke
				(width 0.1)
				(type default)
			)
			(layer "B.Fab")
		)
		(fp_line
			(start -0.67945 -0.3048)
			(end -0.67945 0.3048)
			(stroke
				(width 0.1)
				(type default)
			)
			(layer "B.Fab")
		)
		(fp_line
			(start 0.12065 -0.2794)
			(end -0.12065 -0.2794)
			(stroke
				(width 0.1)
				(type default)
			)
			(layer "B.Fab")
		)
		(fp_line
			(start -0.12065 -0.2794)
			(end -0.12065 -0.3048)
			(stroke
				(width 0.1)
				(type default)
			)
			(layer "B.Fab")
		)
		(fp_line
			(start 0.12065 0.2794)
			(end 0.12065 0.3048)
			(stroke
				(width 0.1)
				(type default)
			)
			(layer "B.Fab")
		)
		(fp_line
			(start -0.120396 0.2794)
			(end 0.12065 0.2794)
			(stroke
				(width 0.1)
				(type default)
			)
			(layer "B.Fab")
		)
		(fp_line
			(start 0.67945 0.3048)
			(end 0.67945 -0.305054)
			(stroke
				(width 0.1)
				(type default)
			)
			(layer "B.Fab")
		)
		(fp_line
			(start 0.12065 0.3048)
			(end 0.67945 0.3048)
			(stroke
				(width 0.1)
				(type default)
			)
			(layer "B.Fab")
		)
		(fp_line
			(start -0.120396 0.3048)
			(end -0.120396 0.2794)
			(stroke
				(width 0.1)
				(type default)
			)
			(layer "B.Fab")
		)
		(fp_line
			(start -0.67945 0.3048)
			(end -0.120396 0.3048)
			(stroke
				(width 0.1)
				(type default)
			)
			(layer "B.Fab")
		)
		(pad "1" smd circle
			(at 0.40005 0 270)
			(size 0 0)
			(layers "B.Cu" "B.Mask" "B.Paste")
			(net "SMB_HOST_3V3AUX_SCL")
		)
		(pad "2" smd circle
			(at -0.40005 0 270)
			(size 0 0)
			(layers "B.Cu" "B.Mask" "B.Paste")
			(net "SMB_HOST_3V3AUX_SCL_R5")
		)
	)
)
